#ISCELL
  mstr_misc dns *
  *
#ISCELL
  mstr_symbols cad_note *
  *
#ISCELL
  mstr_symbols design_note *
  *
#ISCELL
  mstr_symbols intel_corp_bpage *
  *
#CELL
  mstr_digital gtl2014 *
  page152_i1
#ISCELL
  mstr_standard offpage *
  page152_i10
#CELL
  mstr_discrete res *
  page152_i100
#ISCELL
  mstr_standard offpage *
  page152_i101
#CELL
  mstr_discrete res *
  page152_i102
#ISCELL
  mstr_symbols p3v3 *
  page152_i103
#ISCELL
  mstr_symbols pvccio_cpu0 *
  page152_i104
#CELL
  mstr_discrete res *
  page152_i105
#CELL
  w_hdl 374r2f-1-gp *
  page152_i106
#ISCELL
  mstr_standard offpage *
  page152_i11
#ISCELL
  mstr_standard offpage *
  page152_i12
#ISCELL
  mstr_standard offpage *
  page152_i13
#CELL
  mstr_discrete res *
  page152_i14
#CELL
  mstr_discrete res *
  page152_i15
#CELL
  mstr_discrete res *
  page152_i16
#ISCELL
  mstr_symbols gnd *
  page152_i17
#CELL
  mstr_discrete cap *
  page152_i18
#CELL
  mstr_discrete res *
  page152_i2
#ISCELL
  mstr_symbols gnd *
  page152_i20
#ISCELL
  mstr_standard offpage *
  page152_i21
#ISCELL
  mstr_standard offpage *
  page152_i22
#ISCELL
  mstr_standard offpage *
  page152_i23
#ISCELL
  mstr_standard offpage *
  page152_i24
#CELL
  mstr_discrete res *
  page152_i26
#CELL
  dev_discrete cap_a *
  page152_i27
#ISCELL
  mstr_symbols gnd *
  page152_i29
#ISCELL
  mstr_symbols gnd *
  page152_i3
#ISCELL
  mstr_standard offpage *
  page152_i30
#ISCELL
  mstr_standard offpage *
  page152_i4
#CELL
  mstr_discrete res *
  page152_i45
#CELL
  mstr_discrete res *
  page152_i47
#CELL
  mstr_discrete res *
  page152_i49
#ISCELL
  mstr_symbols p3v3 *
  page152_i5
#CELL
  mstr_discrete res *
  page152_i50
#CELL
  mstr_discrete res *
  page152_i51
#ISCELL
  mstr_symbols pvccio_cpu0 *
  page152_i52
#CELL
  mstr_discrete res *
  page152_i53
#CELL
  mstr_discrete res *
  page152_i54
#ISCELL
  mstr_symbols pvccio_cpu1 *
  page152_i55
#CELL
  mstr_discrete res *
  page152_i56
#CELL
  mstr_discrete res *
  page152_i57
#CELL
  mstr_discrete res *
  page152_i58
#CELL
  mstr_discrete res *
  page152_i59
#CELL
  mstr_discrete res *
  page152_i6
#ISCELL
  mstr_symbols pvccio_cpu0 *
  page152_i60
#CELL
  mstr_discrete res *
  page152_i61
#CELL
  mstr_discrete res *
  page152_i62
#ISCELL
  mstr_symbols pvccio_cpu1 *
  page152_i63
#CELL
  mstr_discrete res *
  page152_i64
#CELL
  mstr_discrete res *
  page152_i65
#CELL
  mstr_discrete res *
  page152_i66
#CELL
  mstr_discrete res *
  page152_i67
#CELL
  mstr_discrete res *
  page152_i68
#CELL
  mstr_discrete res *
  page152_i69
#CELL
  mstr_discrete res *
  page152_i70
#CELL
  mstr_discrete res *
  page152_i71
#CELL
  mstr_discrete res *
  page152_i72
#CELL
  mstr_discrete res *
  page152_i73
#CELL
  mstr_discrete res *
  page152_i74
#ISCELL
  mstr_standard offpage *
  page152_i75
#ISCELL
  mstr_standard offpage *
  page152_i76
#ISCELL
  mstr_standard offpage *
  page152_i77
#ISCELL
  mstr_standard offpage *
  page152_i78
#CELL
  mstr_discrete res *
  page152_i79
#ISCELL
  mstr_standard offpage *
  page152_i85
#ISCELL
  mstr_standard offpage *
  page152_i87
#ISCELL
  mstr_standard offpage *
  page152_i89
#ISCELL
  mstr_standard offpage *
  page152_i91
#CELL
  mstr_discrete res *
  page152_i92
#CELL
  mstr_discrete res *
  page152_i93
#CELL
  mstr_discrete res *
  page152_i94
#CELL
  mstr_discrete res *
  page152_i95
#ISCELL
  mstr_standard offpage *
  page152_i96
#ISCELL
  mstr_standard offpage *
  page152_i97
#CELL
  mstr_discrete res *
  page152_i98
#ISCELL
  mstr_standard offpage *
  page152_i99
